(kicad_pcb
	(version 20260206)
	(generator "pcbnew")
	(generator_version "10.0")
	(general
		(thickness 1.6)
		(legacy_teardrops no)
	)
	(paper "A4")
	(title_block
		(title "Wiwynn_Tioga_Pass_MB.brd")
		(comment 1 "Tioga Pass / footprints 958-963 of 4770")
	)
	(layers
		(0 "F.Cu" signal "TOP")
		(4 "In1.Cu" signal "L2GND")
		(6 "In2.Cu" signal "L3")
		(8 "In3.Cu" signal "L4GND")
		(10 "In4.Cu" signal "L5")
		(12 "In5.Cu" signal "L6GND")
		(14 "In6.Cu" signal "L7VCC")
		(16 "In7.Cu" signal "L8VCC")
		(18 "In8.Cu" signal "L9GND")
		(20 "In9.Cu" signal "L10")
		(22 "In10.Cu" signal "L11GND")
		(24 "In11.Cu" signal "L12")
		(26 "In12.Cu" signal "L13GND")
		(2 "B.Cu" signal "BOTTOM")
		(9 "F.Adhes" user "F.Adhesive")
		(11 "B.Adhes" user "B.Adhesive")
		(13 "F.Paste" user "Package Geometry/Pastemask Top")
		(15 "B.Paste" user "Package Geometry/Pastemask Bottom")
		(5 "F.SilkS" user "Ref Des/Silkscreen Top")
		(7 "B.SilkS" user "Ref Des/Silkscreen Bottom")
		(1 "F.Mask" user "Board Geometry/Soldermask Top")
		(3 "B.Mask" user "Board Geometry/Soldermask Bottom")
		(17 "Dwgs.User" user "User.Drawings")
		(19 "Cmts.User" user "User.Comments")
		(21 "Eco1.User" user "User.Eco1")
		(23 "Eco2.User" user "User.Eco2")
		(25 "Edge.Cuts" user "Board Geometry/Outline")
		(27 "Margin" user)
		(31 "F.CrtYd" user "Package Geometry/Place Bound Top")
		(29 "B.CrtYd" user "Package Geometry/Place Bound Bottom")
		(35 "F.Fab" user "Ref Des/Assembly Top")
		(33 "B.Fab" user "Ref Des/Assembly Bottom")
	)
	(footprint ""
		(layer "F.Cu")
		(at 414.8455 -109.728 90)
		(property "Reference" "R8E24"
			(at 0 0 90)
			(layer "F.SilkS")
			(hide yes)
			(effects
				(font
					(size 1.27 1.27)
				)
			)
		)
		(property "Value" ""
			(at 0 0 90)
			(layer "F.Fab")
			(effects
				(font
					(size 1.27 1.27)
				)
			)
		)
		(duplicate_pad_numbers_are_jumpers no)
		(fp_poly
			(pts
				(xy -0.2794 -0.1016) (xy 0.2794 -0.1016) (xy 0.2794 0.9906) (xy -0.2794 0.9906)
			)
			(stroke
				(width 0)
				(type default)
			)
			(fill no)
			(layer "F.CrtYd")
		)
		(fp_line
			(start 0.2794 -0.1016)
			(end -0.2794 -0.1016)
			(stroke
				(width 0.1)
				(type default)
			)
			(layer "F.Fab")
		)
		(fp_line
			(start -0.2794 -0.1016)
			(end -0.2794 0.9906)
			(stroke
				(width 0.1)
				(type default)
			)
			(layer "F.Fab")
		)
		(fp_line
			(start 0.2794 0.9906)
			(end 0.2794 -0.1016)
			(stroke
				(width 0.1)
				(type default)
			)
			(layer "F.Fab")
		)
		(fp_line
			(start -0.2794 0.9906)
			(end 0.2794 0.9906)
			(stroke
				(width 0.1)
				(type default)
			)
			(layer "F.Fab")
		)
		(pad "1" smd rect
			(at 0 0 90)
			(size 0.508 0.508)
			(layers "F.Cu" "F.Mask" "F.Paste")
			(net "IRQ_BMC_PCH_NMI_STBY_N")
		)
		(pad "2" smd rect
			(at 0 0.889 90)
			(size 0.508 0.508)
			(layers "F.Cu" "F.Mask" "F.Paste")
			(net "IRQ_BMC_PCH_NMI_STBY_R_N")
		)
		(zone
			(layer "F.Cu")
			(hatch none 0.5)
			(connect_pads
				(clearance 0)
			)
			(min_thickness 0.25)
			(keepout
				(tracks allowed)
				(vias not_allowed)
				(pads allowed)
				(copperpour not_allowed)
				(footprints allowed)
			)
			(placement
				(enabled no)
				(sheetname "")
			)
			(fill
				(thermal_gap 0.5)
				(thermal_bridge_width 0.5)
				(island_removal_mode 0)
			)
			(polygon
				(pts
					(xy 415.0995 -109.474) (xy 415.0995 -109.982) (xy 415.4805 -109.982) (xy 415.4805 -109.474)
				)
			)
		)
		(zone
			(layer "F.Cu")
			(hatch none 0.5)
			(connect_pads
				(clearance 0)
			)
			(min_thickness 0.25)
			(keepout
				(tracks not_allowed)
				(vias allowed)
				(pads allowed)
				(copperpour not_allowed)
				(footprints allowed)
			)
			(placement
				(enabled no)
				(sheetname "")
			)
			(fill
				(thermal_gap 0.5)
				(thermal_bridge_width 0.5)
				(island_removal_mode 0)
			)
			(polygon
				(pts
					(xy 415.4805 -109.474) (xy 415.4805 -109.982) (xy 415.0995 -109.982) (xy 415.0995 -109.474)
				)
			)
		)
	)
	(footprint ""
		(layer "F.Cu")
		(at 349.886016 -16.19631)
		(property "Reference" "R12W5"
			(at 0 0 0)
			(layer "F.SilkS")
			(hide yes)
			(effects
				(font
					(size 1.27 1.27)
				)
			)
		)
		(property "Value" "*"
			(at 0.064008 -4.108196 0)
			(unlocked yes)
			(layer "F.Fab")
			(hide yes)
			(effects
				(font
					(size 1.27 1.016)
					(thickness 0.1524)
				)
			)
		)
		(property "Device Type" "665KR2B-GP_SMD-RG2-665KR2B-GP,A"
			(at 0.064008 -5.632196 0)
			(unlocked yes)
			(layer "F.Fab")
			(hide yes)
			(effects
				(font
					(size 1.27 1.016)
					(thickness 0.1524)
				)
			)
		)
		(duplicate_pad_numbers_are_jumpers no)
		(fp_line
			(start -0.508 -0.9398)
			(end -0.508 0.9398)
			(stroke
				(width 0.1524)
				(type default)
			)
			(layer "F.SilkS")
		)
		(fp_line
			(start 0.508 -0.9398)
			(end -0.508 -0.9398)
			(stroke
				(width 0.1524)
				(type default)
			)
			(layer "F.SilkS")
		)
		(fp_rect
			(start -0.508 0.9398)
			(end 0.508 -0.9398)
			(stroke
				(width 0)
				(type default)
			)
			(fill no)
			(layer "F.CrtYd")
		)
		(fp_rect
			(start -0.508 0.9398)
			(end 0.508 -0.9398)
			(stroke
				(width 0)
				(type default)
			)
			(fill no)
			(layer "F.Fab")
		)
		(pad "1" smd custom
			(at 0 -0.4445)
			(size 0.1397 0.1397)
			(layers "F.Cu" "F.Mask" "F.Paste")
			(net "VR_PVDDQ_ABC_AIINSEN")
			(options
				(clearance outline)
				(anchor circle)
			)
			(primitives
				(gr_poly
					(pts
						(arc
							(start -0.1778 -0.2794)
							(mid -0.249642 -0.249642)
							(end -0.2794 -0.1778)
						)
						(arc
							(start -0.2794 0.1778)
							(mid -0.249642 0.249642)
							(end -0.1778 0.2794)
						)
						(arc
							(start 0.1778 0.2794)
							(mid 0.249642 0.249642)
							(end 0.2794 0.1778)
						)
						(arc
							(start 0.2794 -0.1778)
							(mid 0.249642 -0.249642)
							(end 0.1778 -0.2794)
						)
					)
					(width 0)
					(fill yes)
				)
			)
		)
		(pad "2" smd custom
			(at 0 0.4445)
			(size 0.1397 0.1397)
			(layers "F.Cu" "F.Mask" "F.Paste")
			(net "VR_PVDDQ_ABC_VINSEN")
			(options
				(clearance outline)
				(anchor circle)
			)
			(primitives
				(gr_poly
					(pts
						(arc
							(start -0.1778 -0.2794)
							(mid -0.249642 -0.249642)
							(end -0.2794 -0.1778)
						)
						(arc
							(start -0.2794 0.1778)
							(mid -0.249642 0.249642)
							(end -0.1778 0.2794)
						)
						(arc
							(start 0.1778 0.2794)
							(mid 0.249642 0.249642)
							(end 0.2794 0.1778)
						)
						(arc
							(start 0.2794 -0.1778)
							(mid 0.249642 -0.249642)
							(end 0.1778 -0.2794)
						)
					)
					(width 0)
					(fill yes)
				)
			)
		)
	)
	(footprint ""
		(layer "F.Cu")
		(at 171.704 -70.6374 180)
		(property "Reference" "C4D32"
			(at 0 0 180)
			(layer "F.SilkS")
			(hide yes)
			(effects
				(font
					(size 1.27 1.27)
				)
			)
		)
		(property "Value" ""
			(at 0 0 180)
			(layer "F.Fab")
			(effects
				(font
					(size 1.27 1.27)
				)
			)
		)
		(duplicate_pad_numbers_are_jumpers no)
		(fp_poly
			(pts
				(xy 0.3048 -0.1016) (xy 0.3048 0.9906) (xy -0.3048 0.9906) (xy -0.3048 -0.1016)
			)
			(stroke
				(width 0)
				(type default)
			)
			(fill no)
			(layer "F.CrtYd")
		)
		(fp_line
			(start 0.3048 0.9906)
			(end 0.3048 -0.1016)
			(stroke
				(width 0.1)
				(type default)
			)
			(layer "F.Fab")
		)
		(fp_line
			(start 0.3048 -0.1016)
			(end -0.3048 -0.1016)
			(stroke
				(width 0.1)
				(type default)
			)
			(layer "F.Fab")
		)
		(fp_line
			(start -0.3048 0.9906)
			(end 0.3048 0.9906)
			(stroke
				(width 0.1)
				(type default)
			)
			(layer "F.Fab")
		)
		(fp_line
			(start -0.3048 -0.1016)
			(end -0.3048 0.9906)
			(stroke
				(width 0.1)
				(type default)
			)
			(layer "F.Fab")
		)
		(pad "1" smd rect
			(at 0 0 180)
			(size 0.508 0.508)
			(layers "F.Cu" "F.Mask" "F.Paste")
			(net "VR_PVCCIO_CPU1_VD12")
		)
		(pad "2" smd rect
			(at 0 0.889 180)
			(size 0.508 0.508)
			(layers "F.Cu" "F.Mask" "F.Paste")
			(net "GND")
		)
		(zone
			(layer "F.Cu")
			(hatch none 0.5)
			(connect_pads
				(clearance 0)
			)
			(min_thickness 0.25)
			(keepout
				(tracks not_allowed)
				(vias allowed)
				(pads allowed)
				(copperpour not_allowed)
				(footprints allowed)
			)
			(placement
				(enabled no)
				(sheetname "")
			)
			(fill
				(thermal_gap 0.5)
				(thermal_bridge_width 0.5)
				(island_removal_mode 0)
			)
			(polygon
				(pts
					(xy 171.958 -71.2724) (xy 171.45 -71.2724) (xy 171.45 -70.8914) (xy 171.958 -70.8914)
				)
			)
		)
		(zone
			(layer "F.Cu")
			(hatch none 0.5)
			(connect_pads
				(clearance 0)
			)
			(min_thickness 0.25)
			(keepout
				(tracks allowed)
				(vias not_allowed)
				(pads allowed)
				(copperpour not_allowed)
				(footprints allowed)
			)
			(placement
				(enabled no)
				(sheetname "")
			)
			(fill
				(thermal_gap 0.5)
				(thermal_bridge_width 0.5)
				(island_removal_mode 0)
			)
			(polygon
				(pts
					(xy 171.958 -70.8914) (xy 171.45 -70.8914) (xy 171.45 -71.2724) (xy 171.958 -71.2724)
				)
			)
		)
	)
	(footprint ""
		(layer "F.Cu")
		(at 26.66492 -36.964874)
		(property "Reference" "J1F2"
			(at 0 0 0)
			(layer "F.SilkS")
			(hide yes)
			(effects
				(font
					(size 1.27 1.27)
				)
			)
		)
		(property "Value" "*"
			(at -6.3881 -0.97155 0)
			(unlocked yes)
			(layer "F.Fab")
			(hide yes)
			(effects
				(font
					(size 0.889 0.889)
					(thickness 0.1524)
				)
			)
		)
		(property "Device Type" "LOTES-CON4-S1-GP_CONN-G7-LOTESA"
			(at -6.3881 -2.49555 0)
			(unlocked yes)
			(layer "F.Fab")
			(hide yes)
			(effects
				(font
					(size 0.889 0.889)
					(thickness 0.1524)
				)
			)
		)
		(duplicate_pad_numbers_are_jumpers no)
		(fp_line
			(start -5.334 -3.302)
			(end 5.334 -3.302)
			(stroke
				(width 0.508)
				(type default)
			)
			(layer "F.SilkS")
		)
		(fp_line
			(start -5.334 -3.1242)
			(end 5.334 -3.1242)
			(stroke
				(width 0.1524)
				(type default)
			)
			(layer "F.SilkS")
		)
		(fp_line
			(start -5.334 3.0226)
			(end -5.334 -3.1242)
			(stroke
				(width 0.1524)
				(type default)
			)
			(layer "F.SilkS")
		)
		(fp_line
			(start 4.191 3.16484)
			(end 5.461 3.16484)
			(stroke
				(width 0.4064)
				(type default)
			)
			(layer "F.SilkS")
		)
		(fp_line
			(start 5.334 -3.1242)
			(end 5.334 3.0226)
			(stroke
				(width 0.1524)
				(type default)
			)
			(layer "F.SilkS")
		)
		(fp_line
			(start 5.334 3.0226)
			(end -5.334 3.0226)
			(stroke
				(width 0.1524)
				(type default)
			)
			(layer "F.SilkS")
		)
		(fp_line
			(start 5.461 3.16484)
			(end 5.461 1.89484)
			(stroke
				(width 0.4064)
				(type default)
			)
			(layer "F.SilkS")
		)
		(fp_circle
			(center -3.81 0)
			(end -2.5527 0)
			(stroke
				(width 0.3048)
				(type default)
			)
			(fill no)
			(layer "F.SilkS")
		)
		(fp_circle
			(center -1.27 0)
			(end -0.0127 0)
			(stroke
				(width 0.3048)
				(type default)
			)
			(fill no)
			(layer "F.SilkS")
		)
		(fp_circle
			(center 1.27 0)
			(end 2.5273 0)
			(stroke
				(width 0.3048)
				(type default)
			)
			(fill no)
			(layer "F.SilkS")
		)
		(fp_circle
			(center 3.81 0)
			(end 5.0673 0)
			(stroke
				(width 0.3048)
				(type default)
			)
			(fill no)
			(layer "F.SilkS")
		)
		(fp_rect
			(start -5.08 2.54)
			(end 5.08 -2.8702)
			(stroke
				(width 0)
				(type default)
			)
			(fill no)
			(layer "F.CrtYd")
		)
		(fp_poly
			(pts
				(xy -5.588 3.2766) (xy -5.588 -3.3782) (xy 5.588 -3.3782) (xy 5.588 -0.00635) (xy 5.08 -0.00635)
				(xy 5.08 -2.8702) (xy -5.08 -2.8702) (xy -5.08 2.54) (xy 5.08 2.54) (xy 5.08 0.00635) (xy 5.588 0.00635)
				(xy 5.588 3.2766)
			)
			(stroke
				(width 0)
				(type default)
			)
			(fill no)
			(layer "F.CrtYd")
		)
		(fp_rect
			(start -5.588 3.2766)
			(end 5.588 -3.3782)
			(stroke
				(width 0)
				(type default)
			)
			(fill no)
			(layer "F.Fab")
		)
		(pad "" np_thru_hole circle
			(at -1.27 2.189988)
			(size 0.254 0.254)
			(drill 1.1684)
			(layers "*.Cu" "*.Mask")
			(clearance 0.8128)
			(thermal_gap 0.8128)
		)
		(pad "1" thru_hole circle
			(at 3.81 0)
			(size 1.8034 1.8034)
			(drill 1.1684)
			(layers "*.Cu" "*.Mask")
			(remove_unused_layers no)
			(net "GND")
			(clearance 0.1905)
			(thermal_gap 0.1905)
		)
		(pad "2" thru_hole circle
			(at 1.27 0)
			(size 1.8034 1.8034)
			(drill 1.1684)
			(layers "*.Cu" "*.Mask")
			(remove_unused_layers no)
			(net "P12V_FAN")
			(clearance 0.1905)
			(thermal_gap 0.1905)
		)
		(pad "3" thru_hole circle
			(at -1.27 0)
			(size 1.8034 1.8034)
			(drill 1.1684)
			(layers "*.Cu" "*.Mask")
			(remove_unused_layers no)
			(net "FAN_TACH0_CPU0_D1")
			(clearance 0.1905)
			(thermal_gap 0.1905)
		)
		(pad "4" thru_hole circle
			(at -3.81 0)
			(size 1.8034 1.8034)
			(drill 1.1684)
			(layers "*.Cu" "*.Mask")
			(remove_unused_layers no)
			(net "FAN_PWM_OUT_SYS0_R")
			(clearance 0.1905)
			(thermal_gap 0.1905)
		)
		(zone
			(layers "F.Cu" "B.Cu" "In1.Cu" "In2.Cu" "In3.Cu" "In4.Cu" "In5.Cu" "In6.Cu"
				"In7.Cu" "In8.Cu" "In9.Cu" "In10.Cu" "In11.Cu" "In12.Cu"
			)
			(hatch none 0.5)
			(connect_pads
				(clearance 0)
			)
			(min_thickness 0.25)
			(keepout
				(tracks not_allowed)
				(vias allowed)
				(pads allowed)
				(copperpour not_allowed)
				(footprints allowed)
			)
			(placement
				(enabled no)
				(sheetname "")
			)
			(fill
				(thermal_gap 0.5)
				(thermal_bridge_width 0.5)
				(island_removal_mode 0)
			)
			(polygon
				(pts
					(arc
						(start 26.28392 -34.774886)
						(mid 24.50592 -34.774886)
						(end 26.28392 -34.774886)
					)
				)
			)
		)
	)
	(footprint ""
		(layer "F.Cu")
		(at 183.769 -53.594 -90)
		(property "Reference" "RT41"
			(at 1.01473 0.656336 180)
			(unlocked yes)
			(layer "F.SilkS")
			(effects
				(font
					(size 0.4064 0.254)
					(thickness 0.1524)
				)
			)
		)
		(property "Value" ""
			(at 0 0 270)
			(layer "F.Fab")
			(effects
				(font
					(size 1.27 1.27)
				)
			)
		)
		(duplicate_pad_numbers_are_jumpers no)
		(fp_poly
			(pts
				(xy -0.4953 -0.2032) (xy 0.4953 -0.2032) (xy 0.4953 1.6002) (xy -0.4953 1.6002)
			)
			(stroke
				(width 0)
				(type default)
			)
			(fill no)
			(layer "F.CrtYd")
		)
		(fp_line
			(start -0.4953 1.6002)
			(end -0.4953 -0.2032)
			(stroke
				(width 0.1)
				(type default)
			)
			(layer "F.Fab")
		)
		(fp_line
			(start 0.4953 1.6002)
			(end -0.4953 1.6002)
			(stroke
				(width 0.1)
				(type default)
			)
			(layer "F.Fab")
		)
		(fp_line
			(start -0.4953 -0.2032)
			(end 0.4953 -0.2032)
			(stroke
				(width 0.1)
				(type default)
			)
			(layer "F.Fab")
		)
		(fp_line
			(start 0.4953 -0.2032)
			(end 0.4953 1.6002)
			(stroke
				(width 0.1)
				(type default)
			)
			(layer "F.Fab")
		)
		(pad "1" smd rect
			(at 0 0 270)
			(size 0.762 0.889)
			(layers "F.Cu" "F.Mask" "F.Paste")
			(net "VR_PVCCIO_CPU1_PH1_BOOT")
		)
		(pad "2" smd rect
			(at 0 1.397 270)
			(size 0.762 0.889)
			(layers "F.Cu" "F.Mask" "F.Paste")
			(net "VR_PVCCIO_CPU1_PH1_BOOT_R")
		)
		(zone
			(layer "F.Cu")
			(hatch none 0.5)
			(connect_pads
				(clearance 0)
			)
			(min_thickness 0.25)
			(keepout
				(tracks not_allowed)
				(vias allowed)
				(pads allowed)
				(copperpour not_allowed)
				(footprints allowed)
			)
			(placement
				(enabled no)
				(sheetname "")
			)
			(fill
				(thermal_gap 0.5)
				(thermal_bridge_width 0.5)
				(island_removal_mode 0)
			)
			(polygon
				(pts
					(xy 182.8165 -53.975) (xy 182.8165 -53.213) (xy 183.3245 -53.213) (xy 183.3245 -53.975)
				)
			)
		)
		(zone
			(layer "F.Cu")
			(hatch none 0.5)
			(connect_pads
				(clearance 0)
			)
			(min_thickness 0.25)
			(keepout
				(tracks allowed)
				(vias not_allowed)
				(pads allowed)
				(copperpour not_allowed)
				(footprints allowed)
			)
			(placement
				(enabled no)
				(sheetname "")
			)
			(fill
				(thermal_gap 0.5)
				(thermal_bridge_width 0.5)
				(island_removal_mode 0)
			)
			(polygon
				(pts
					(xy 182.8165 -53.213) (xy 183.3245 -53.213) (xy 183.3245 -53.975) (xy 182.8165 -53.975)
				)
			)
		)
	)
	(footprint ""
		(layer "F.Cu")
		(at 174.6377 -66.191638 -90)
		(property "Reference" "R4D60"
			(at 0 0 270)
			(layer "F.SilkS")
			(hide yes)
			(effects
				(font
					(size 1.27 1.27)
				)
			)
		)
		(property "Value" ""
			(at 0 0 270)
			(layer "F.Fab")
			(effects
				(font
					(size 1.27 1.27)
				)
			)
		)
		(duplicate_pad_numbers_are_jumpers no)
		(fp_poly
			(pts
				(xy -0.2794 -0.1016) (xy 0.2794 -0.1016) (xy 0.2794 0.9906) (xy -0.2794 0.9906)
			)
			(stroke
				(width 0)
				(type default)
			)
			(fill no)
			(layer "F.CrtYd")
		)
		(fp_line
			(start -0.2794 0.9906)
			(end 0.2794 0.9906)
			(stroke
				(width 0.1)
				(type default)
			)
			(layer "F.Fab")
		)
		(fp_line
			(start 0.2794 0.9906)
			(end 0.2794 -0.1016)
			(stroke
				(width 0.1)
				(type default)
			)
			(layer "F.Fab")
		)
		(fp_line
			(start -0.2794 -0.1016)
			(end -0.2794 0.9906)
			(stroke
				(width 0.1)
				(type default)
			)
			(layer "F.Fab")
		)
		(fp_line
			(start 0.2794 -0.1016)
			(end -0.2794 -0.1016)
			(stroke
				(width 0.1)
				(type default)
			)
			(layer "F.Fab")
		)
		(pad "1" smd rect
			(at 0 0 270)
			(size 0.508 0.508)
			(layers "F.Cu" "F.Mask" "F.Paste")
			(net "VR_FET_SW_P12V_STBY_PVCCIN_CPU0")
		)
		(pad "2" smd rect
			(at 0 0.889 270)
			(size 0.508 0.508)
			(layers "F.Cu" "F.Mask" "F.Paste")
			(net "VR_PVCCIO_CPU1_VINSEN")
		)
		(zone
			(layer "F.Cu")
			(hatch none 0.5)
			(connect_pads
				(clearance 0)
			)
			(min_thickness 0.25)
			(keepout
				(tracks not_allowed)
				(vias allowed)
				(pads allowed)
				(copperpour not_allowed)
				(footprints allowed)
			)
			(placement
				(enabled no)
				(sheetname "")
			)
			(fill
				(thermal_gap 0.5)
				(thermal_bridge_width 0.5)
				(island_removal_mode 0)
			)
			(polygon
				(pts
					(xy 174.0027 -66.445638) (xy 174.0027 -65.937638) (xy 174.3837 -65.937638) (xy 174.3837 -66.445638)
				)
			)
		)
		(zone
			(layer "F.Cu")
			(hatch none 0.5)
			(connect_pads
				(clearance 0)
			)
			(min_thickness 0.25)
			(keepout
				(tracks allowed)
				(vias not_allowed)
				(pads allowed)
				(copperpour not_allowed)
				(footprints allowed)
			)
			(placement
				(enabled no)
				(sheetname "")
			)
			(fill
				(thermal_gap 0.5)
				(thermal_bridge_width 0.5)
				(island_removal_mode 0)
			)
			(polygon
				(pts
					(xy 174.3837 -66.445638) (xy 174.3837 -65.937638) (xy 174.0027 -65.937638) (xy 174.0027 -66.445638)
				)
			)
		)
	)
)
